#ISCELL
  pure_quanta quanta_title_block_c *
  *
#CELL
  pure_quanta lcmxo3lf2100c5bg256c *
  page34_i1
#ISCELL
  standard offpage *
  page34_i10
#ISCELL
  standard offpage *
  page34_i105
#ISCELL
  standard offpage *
  page34_i106
#ISCELL
  standard offpage *
  page34_i107
#ISCELL
  standard offpage *
  page34_i11
#ISCELL
  standard offpage *
  page34_i111
#ISCELL
  standard offpage *
  page34_i112
#ISCELL
  standard offpage *
  page34_i113
#ISCELL
  standard offpage *
  page34_i114
#CELL
  pure_quanta q_res *
  page34_i115
#CELL
  pure_quanta q_res *
  page34_i116
#CELL
  pure_quanta q_res *
  page34_i117
#ISCELL
  logical_power universal_power *
  page34_i118
#CELL
  pure_quanta q_res *
  page34_i119
#ISCELL
  standard offpage *
  page34_i12
#ISCELL
  logical_power universal_power *
  page34_i120
#ISCELL
  logical_power universal_gnd *
  page34_i121
#CELL
  pure_quanta q_cap *
  page34_i122
#ISCELL
  logical_power universal_power *
  page34_i123
#ISCELL
  logical_power universal_gnd *
  page34_i124
#ISCELL
  standard offpage *
  page34_i125
#CELL
  pure_quanta q_res *
  page34_i126
#CELL
  pure_quanta osc4_7x25000018 *
  page34_i127
#ISCELL
  logical_power universal_power *
  page34_i128
#ISCELL
  logical_power universal_power *
  page34_i129
#ISCELL
  standard offpage *
  page34_i13
#ISCELL
  standard offpage *
  page34_i130
#ISCELL
  logical_power universal_power *
  page34_i136
#CELL
  pure_quanta q_res *
  page34_i137
#ISCELL
  logical_power universal_power *
  page34_i138
#CELL
  pure_quanta q_res *
  page34_i139
#CELL
  pure_quanta q_cap *
  page34_i140
#ISCELL
  logical_power universal_gnd *
  page34_i141
#ISCELL
  logical_power universal_power *
  page34_i143
#CELL
  pure_quanta q_cap *
  page34_i144
#ISCELL
  standard offpage *
  page34_i145
#CELL
  pure_quanta q_res *
  page34_i147
#ISCELL
  standard offpage *
  page34_i148
#ISCELL
  standard offpage *
  page34_i15
#CELL
  pure_quanta q_res *
  page34_i150
#ISCELL
  standard offpage *
  page34_i151
#ISCELL
  standard offpage *
  page34_i152
#ISCELL
  standard offpage *
  page34_i153
#CELL
  pure_quanta q_res *
  page34_i155
#CELL
  pure_quanta q_res *
  page34_i156
#CELL
  pure_quanta q_res *
  page34_i157
#CELL
  pure_quanta q_res *
  page34_i158
#CELL
  pure_quanta q_res *
  page34_i159
#ISCELL
  standard offpage *
  page34_i16
#CELL
  pure_quanta q_res *
  page34_i160
#CELL
  pure_quanta q_res *
  page34_i161
#CELL
  pure_quanta q_res *
  page34_i162
#CELL
  pure_quanta q_res *
  page34_i163
#CELL
  pure_quanta q_res *
  page34_i164
#CELL
  pure_quanta q_res *
  page34_i165
#CELL
  pure_quanta q_res *
  page34_i166
#CELL
  pure_quanta q_res *
  page34_i167
#CELL
  pure_quanta q_res *
  page34_i168
#CELL
  pure_quanta q_res *
  page34_i17
#ISCELL
  logical_power vccaux15 *
  page34_i18
#ISCELL
  standard offpage *
  page34_i19
#ISCELL
  standard offpage *
  page34_i20
#ISCELL
  standard offpage *
  page34_i21
#ISCELL
  standard offpage *
  page34_i23
#ISCELL
  standard offpage *
  page34_i24
#ISCELL
  standard offpage *
  page34_i25
#ISCELL
  standard offpage *
  page34_i26
#ISCELL
  standard offpage *
  page34_i27
#ISCELL
  standard offpage *
  page34_i30
#CELL
  pure_quanta q_res *
  page34_i35
#CELL
  pure_quanta q_res *
  page34_i37
#ISCELL
  standard offpage *
  page34_i42
#ISCELL
  standard offpage *
  page34_i43
#ISCELL
  standard offpage *
  page34_i44
#ISCELL
  standard offpage *
  page34_i45
#ISCELL
  standard offpage *
  page34_i77
#ISCELL
  standard offpage *
  page34_i78
#ISCELL
  standard offpage *
  page34_i79
#ISCELL
  standard offpage *
  page34_i8
#ISCELL
  standard offpage *
  page34_i80
#ISCELL
  standard offpage *
  page34_i81
#ISCELL
  standard offpage *
  page34_i82
#ISCELL
  standard offpage *
  page34_i83
#ISCELL
  standard offpage *
  page34_i84
#ISCELL
  standard offpage *
  page34_i85
#ISCELL
  standard offpage *
  page34_i86
#ISCELL
  standard offpage *
  page34_i87
#ISCELL
  standard offpage *
  page34_i88
#ISCELL
  standard offpage *
  page34_i89
#ISCELL
  standard offpage *
  page34_i9
#ISCELL
  standard offpage *
  page34_i93
#ISCELL
  standard offpage *
  page34_i96
